# T6G (Grand Teton) — schematic netlist excerpt (pin names and nets, part order shuffled) for the footprints in the layout excerpt that follows; sources: Cadence DE-HDL packaged netlist, KiCad conversion of 04192023_DAF0TMB3IC0_F0TG_MB_C_brd_V02_OCP.brd

PR335  Q_RES  0 5% CHIP  pkg 0402LF  page 211 : A = PVDDCR_CPU0_P1_PVCC ; B = P5V_AUX
H88  HOLE  EMPTY  pkg TH  page 230 : \1\ = GND
PC177  Q_CAP  560PF 50V 10% EMPTY  pkg C0402  page 223 : A = SW_PVDDIO_P1_SW3 ; B = SW_PVDDIO_P1_SW3_RC
R6195  Q_RES  0 5% CHIP  pkg 0201LF  page 180 : A = USB2_CPU0_P0_HUB1_R_DN ; B = USB2_HUB_EXT_DN

(kicad_pcb
	(version 20260206)
	(generator "pcbnew")
	(generator_version "10.0")
	(general
		(thickness 1.6)
		(legacy_teardrops no)
	)
	(paper "A4")
	(title_block
		(title "04192023_DAF0TMB3IC0_F0TG_MB_C_brd_V02_OCP.brd")
		(comment 1 "Grand Teton / footprints 4293-4296 of 8354")
	)
	(layers
		(0 "F.Cu" signal "TOP")
		(4 "In1.Cu" signal "GND")
		(6 "In2.Cu" signal "IN1")
		(8 "In3.Cu" signal "GND1")
		(10 "In4.Cu" signal "IN2")
		(12 "In5.Cu" signal "GND2")
		(14 "In6.Cu" signal "IN3")
		(16 "In7.Cu" signal "GND3")
		(18 "In8.Cu" signal "VCC")
		(20 "In9.Cu" signal "VCC1")
		(22 "In10.Cu" signal "GND4")
		(24 "In11.Cu" signal "IN4")
		(26 "In12.Cu" signal "GND5")
		(28 "In13.Cu" signal "IN5")
		(30 "In14.Cu" signal "GND6")
		(32 "In15.Cu" signal "IN6")
		(34 "In16.Cu" signal "GND7")
		(2 "B.Cu" signal "BOTTOM")
		(9 "F.Adhes" user "F.Adhesive")
		(11 "B.Adhes" user "B.Adhesive")
		(13 "F.Paste" user "Package Geometry/Pastemask Top")
		(15 "B.Paste" user "Package Geometry/Pastemask Bottom")
		(5 "F.SilkS" user "Ref Des/Silkscreen Top")
		(7 "B.SilkS" user "Ref Des/Silkscreen Bottom")
		(1 "F.Mask" user "Board Geometry/Soldermask Top")
		(3 "B.Mask" user "Board Geometry/Soldermask Bottom")
		(17 "Dwgs.User" user "User.Drawings")
		(19 "Cmts.User" user "User.Comments")
		(21 "Eco1.User" user "User.Eco1")
		(23 "Eco2.User" user "User.Eco2")
		(25 "Edge.Cuts" user "Board Geometry/Outline")
		(27 "Margin" user)
		(31 "F.CrtYd" user "Package Geometry/Place Bound Top")
		(29 "B.CrtYd" user "Package Geometry/Place Bound Bottom")
		(35 "F.Fab" user "Ref Des/Assembly Top")
		(33 "B.Fab" user "Ref Des/Assembly Bottom")
	)
	(footprint ""
		(layer "F.Cu")
		(at 33.187132 -343.716864 180)
		(property "Reference" "PC177"
			(at 0 0 180)
			(layer "F.SilkS")
			(hide yes)
			(effects
				(font
					(size 1.27 1.27)
				)
			)
		)
		(property "Value" ""
			(at 0 0 180)
			(layer "F.Fab")
			(effects
				(font
					(size 1.27 1.27)
				)
			)
		)
		(duplicate_pad_numbers_are_jumpers no)
		(fp_line
			(start 0.7874 0.4064)
			(end -0.7874 0.4064)
			(stroke
				(width 0.1524)
				(type default)
			)
			(layer "F.SilkS")
		)
		(fp_line
			(start 0.7874 -0.4064)
			(end 0.7874 0.4064)
			(stroke
				(width 0.1524)
				(type default)
			)
			(layer "F.SilkS")
		)
		(fp_line
			(start -0.7874 0.4064)
			(end -0.7874 -0.4064)
			(stroke
				(width 0.1524)
				(type default)
			)
			(layer "F.SilkS")
		)
		(fp_line
			(start -0.7874 -0.4064)
			(end 0.7874 -0.4064)
			(stroke
				(width 0.1524)
				(type default)
			)
			(layer "F.SilkS")
		)
		(fp_line
			(start 0.67945 0.3048)
			(end 0.120396 0.3048)
			(stroke
				(width 0.1)
				(type default)
			)
			(layer "F.Fab")
		)
		(fp_line
			(start 0.67945 -0.3048)
			(end 0.67945 0.3048)
			(stroke
				(width 0.1)
				(type default)
			)
			(layer "F.Fab")
		)
		(fp_line
			(start 0.12065 -0.2794)
			(end 0.12065 -0.3048)
			(stroke
				(width 0.1)
				(type default)
			)
			(layer "F.Fab")
		)
		(fp_line
			(start 0.12065 -0.3048)
			(end 0.67945 -0.3048)
			(stroke
				(width 0.1)
				(type default)
			)
			(layer "F.Fab")
		)
		(fp_line
			(start 0.120396 0.3048)
			(end 0.120396 0.2794)
			(stroke
				(width 0.1)
				(type default)
			)
			(layer "F.Fab")
		)
		(fp_line
			(start 0.120396 0.2794)
			(end -0.12065 0.2794)
			(stroke
				(width 0.1)
				(type default)
			)
			(layer "F.Fab")
		)
		(fp_line
			(start -0.12065 0.3048)
			(end -0.67945 0.3048)
			(stroke
				(width 0.1)
				(type default)
			)
			(layer "F.Fab")
		)
		(fp_line
			(start -0.12065 0.2794)
			(end -0.12065 0.3048)
			(stroke
				(width 0.1)
				(type default)
			)
			(layer "F.Fab")
		)
		(fp_line
			(start -0.12065 -0.2794)
			(end 0.12065 -0.2794)
			(stroke
				(width 0.1)
				(type default)
			)
			(layer "F.Fab")
		)
		(fp_line
			(start -0.12065 -0.305054)
			(end -0.12065 -0.2794)
			(stroke
				(width 0.1)
				(type default)
			)
			(layer "F.Fab")
		)
		(fp_line
			(start -0.67945 0.3048)
			(end -0.67945 -0.305054)
			(stroke
				(width 0.1)
				(type default)
			)
			(layer "F.Fab")
		)
		(fp_line
			(start -0.67945 -0.305054)
			(end -0.12065 -0.305054)
			(stroke
				(width 0.1)
				(type default)
			)
			(layer "F.Fab")
		)
		(pad "1" smd circle
			(at -0.40005 0 180)
			(size 0 0)
			(layers "F.Cu" "F.Mask" "F.Paste")
			(net "SW_PVDDIO_P1_SW3")
		)
		(pad "2" smd circle
			(at 0.40005 0 180)
			(size 0 0)
			(layers "F.Cu" "F.Mask" "F.Paste")
			(net "SW_PVDDIO_P1_SW3_RC")
		)
	)
	(footprint ""
		(layer "F.Cu")
		(at 135.36168 -29.01442 -90)
		(property "Reference" "R6195"
			(at 0 0 270)
			(layer "F.SilkS")
			(hide yes)
			(effects
				(font
					(size 1.27 1.27)
				)
			)
		)
		(property "Value" ""
			(at 0 0 270)
			(layer "F.Fab")
			(effects
				(font
					(size 1.27 1.27)
				)
			)
		)
		(duplicate_pad_numbers_are_jumpers no)
		(fp_line
			(start -0.32512 0.175006)
			(end -0.32512 -0.175006)
			(stroke
				(width 0.1)
				(type default)
			)
			(layer "F.Fab")
		)
		(fp_line
			(start 0.32512 0.175006)
			(end -0.32512 0.175006)
			(stroke
				(width 0.1)
				(type default)
			)
			(layer "F.Fab")
		)
		(fp_line
			(start -0.32512 -0.175006)
			(end 0.32512 -0.175006)
			(stroke
				(width 0.1)
				(type default)
			)
			(layer "F.Fab")
		)
		(fp_line
			(start 0.32512 -0.175006)
			(end 0.32512 0.175006)
			(stroke
				(width 0.1)
				(type default)
			)
			(layer "F.Fab")
		)
		(pad "1" smd rect
			(at -0.2667 0 270)
			(size 0.3048 0.381)
			(layers "F.Cu" "F.Mask" "F.Paste")
			(net "USB2_CPU0_P0_HUB1_R_DN")
		)
		(pad "2" smd rect
			(at 0.2667 0 90)
			(size 0.3048 0.381)
			(layers "F.Cu" "F.Mask" "F.Paste")
			(net "USB2_HUB_EXT_DN")
		)
	)
	(footprint ""
		(layer "F.Cu")
		(at 10.339832 -160.499806)
		(property "Reference" "H88"
			(at -4.6863 -5.71119 0)
			(unlocked yes)
			(layer "F.SilkS")
			(effects
				(font
					(size 0.7874 0.5842)
					(thickness 0.1524)
				)
				(justify left)
			)
		)
		(property "Value" ""
			(at 0 0 0)
			(layer "F.Fab")
			(effects
				(font
					(size 1.27 1.27)
				)
			)
		)
		(duplicate_pad_numbers_are_jumpers no)
		(pad "1" thru_hole circle
			(at 0 0)
			(size 10.0076 10.0076)
			(drill 5.6134)
			(layers "*.Cu" "*.Mask")
			(remove_unused_layers no)
			(net "GND")
			(clearance -1.9431)
		)
	)
	(footprint ""
		(layer "F.Cu")
		(at 138.016234 -151.619712 -90)
		(property "Reference" "PR335"
			(at 0 0 270)
			(layer "F.SilkS")
			(hide yes)
			(effects
				(font
					(size 1.27 1.27)
				)
			)
		)
		(property "Value" ""
			(at 0 0 270)
			(layer "F.Fab")
			(effects
				(font
					(size 1.27 1.27)
				)
			)
		)
		(duplicate_pad_numbers_are_jumpers no)
		(fp_line
			(start -0.7874 0.4064)
			(end -0.7874 -0.4064)
			(stroke
				(width 0.1524)
				(type default)
			)
			(layer "F.SilkS")
		)
		(fp_line
			(start 0.7874 0.4064)
			(end -0.7874 0.4064)
			(stroke
				(width 0.1524)
				(type default)
			)
			(layer "F.SilkS")
		)
		(fp_line
			(start -0.7874 -0.4064)
			(end 0.7874 -0.4064)
			(stroke
				(width 0.1524)
				(type default)
			)
			(layer "F.SilkS")
		)
		(fp_line
			(start 0.7874 -0.4064)
			(end 0.7874 0.4064)
			(stroke
				(width 0.1524)
				(type default)
			)
			(layer "F.SilkS")
		)
		(fp_line
			(start -0.67945 0.3048)
			(end -0.67945 -0.305054)
			(stroke
				(width 0.1)
				(type default)
			)
			(layer "F.Fab")
		)
		(fp_line
			(start -0.12065 0.3048)
			(end -0.67945 0.3048)
			(stroke
				(width 0.1)
				(type default)
			)
			(layer "F.Fab")
		)
		(fp_line
			(start 0.120396 0.3048)
			(end 0.120396 0.2794)
			(stroke
				(width 0.1)
				(type default)
			)
			(layer "F.Fab")
		)
		(fp_line
			(start 0.67945 0.3048)
			(end 0.120396 0.3048)
			(stroke
				(width 0.1)
				(type default)
			)
			(layer "F.Fab")
		)
		(fp_line
			(start -0.12065 0.2794)
			(end -0.12065 0.3048)
			(stroke
				(width 0.1)
				(type default)
			)
			(layer "F.Fab")
		)
		(fp_line
			(start 0.120396 0.2794)
			(end -0.12065 0.2794)
			(stroke
				(width 0.1)
				(type default)
			)
			(layer "F.Fab")
		)
		(fp_line
			(start -0.12065 -0.2794)
			(end 0.12065 -0.2794)
			(stroke
				(width 0.1)
				(type default)
			)
			(layer "F.Fab")
		)
		(fp_line
			(start 0.12065 -0.2794)
			(end 0.12065 -0.3048)
			(stroke
				(width 0.1)
				(type default)
			)
			(layer "F.Fab")
		)
		(fp_line
			(start 0.12065 -0.3048)
			(end 0.67945 -0.3048)
			(stroke
				(width 0.1)
				(type default)
			)
			(layer "F.Fab")
		)
		(fp_line
			(start 0.67945 -0.3048)
			(end 0.67945 0.3048)
			(stroke
				(width 0.1)
				(type default)
			)
			(layer "F.Fab")
		)
		(fp_line
			(start -0.67945 -0.305054)
			(end -0.12065 -0.305054)
			(stroke
				(width 0.1)
				(type default)
			)
			(layer "F.Fab")
		)
		(fp_line
			(start -0.12065 -0.305054)
			(end -0.12065 -0.2794)
			(stroke
				(width 0.1)
				(type default)
			)
			(layer "F.Fab")
		)
		(pad "1" smd circle
			(at -0.40005 0 270)
			(size 0 0)
			(layers "F.Cu" "F.Mask" "F.Paste")
			(net "PVDDCR_CPU0_P1_PVCC")
		)
		(pad "2" smd circle
			(at 0.40005 0 270)
			(size 0 0)
			(layers "F.Cu" "F.Mask" "F.Paste")
			(net "P5V_AUX")
		)
	)
)
